# BASEBOARD_FAB2 (Tioga Pass) — schematic parts with pin connectivity, parts 1838–1995 of 4751; source: Cadence DE-HDL packaged netlist (pstxprt.dat, pstxnet.dat, pstchip.dat)

C9L1  CAP_A  0.01UF 25V 10% X7R  pkg 0402V  page 88 : 1 = M_M_VREF ; 2 = GND
C9L2  CAPP  470UF 2.5V 20% ALUM  pkg 3018  page 228 : 1 = PVDDQ_KLM ; 2 = GND
C9L3  CAP_A  0.01UF 25V 10% X7R  pkg 0402V  page 100 : 1 = M_M_CPU_VREF ; 2 = GND
C9L4  CAPP  470UF 2.5V 20% ALUM  pkg 3018  page 228 : 1 = PVDDQ_KLM ; 2 = GND
C9L5  CAP  10UF 16V 10% X6S  pkg 0805  page 227 : 1 = VR_FET_SW_P12V_STBY_PVDDQ_KLM ; 2 = GND
C9L6  CAP  10UF 16V 10% X6S  pkg 0805  page 227 : 1 = VR_FET_SW_P12V_STBY_PVDDQ_KLM ; 2 = GND
C9L7  CAP_A  0.01UF 25V 10% X7R  pkg 0402V  page 85 : 1 = M_L_VREF ; 2 = GND
C9L8  CAP_A  0.01UF 25V 10% X7R  pkg 0402V  page 100 : 1 = M_L_CPU_VREF ; 2 = GND
C9L9  CAPP  470UF 2.5V 20% ALUM  pkg 3018  page 228 : 1 = PVDDQ_KLM ; 2 = GND
C9L10  CAP  10UF 16V 10% X6S  pkg 0805  page 227 : 1 = VR_FET_SW_P12V_STBY_PVDDQ_KLM ; 2 = GND
C9L11  CAP  10UF 16V 10% X6S  pkg 0805  page 227 : 1 = VR_FET_SW_P12V_STBY_PVDDQ_KLM ; 2 = GND
C9L12  CAPP  470UF 2.5V 20% ALUM  pkg 3018  page 228 : 1 = PVDDQ_KLM ; 2 = GND
C9L13  CAP  10UF 16V 10% X6S  pkg 0805  page 227 : 1 = VR_FET_SW_P12V_STBY_PVDDQ_KLM ; 2 = GND
C9L14  CAP  10UF 16V 10% X6S  pkg 0805  page 227 : 1 = VR_FET_SW_P12V_STBY_PVDDQ_KLM ; 2 = GND
C9M1  CAP_A  0.01UF 25V 10% X7R  pkg 0402V  page 84 : 1 = M_K_VREF ; 2 = GND
C9M2  CAP_A  0.01UF 25V 10% X7R  pkg 0402V  page 100 : 1 = M_K_CPU_VREF ; 2 = GND
C9M3  CAPP  68UF 16V 20% TANT  pkg 3018  page 195 : 1 = P12V_STBY ; 2 = GND
C9M4  CAP  10UF 16V 10% X6S  pkg 0805  page 161 : 1 = P12V_FAN ; 2 = GND
C9M5  CAP_A  0.1UF 16V 10% X7R  pkg 0402V  page 161 : 1 = P12V_FAN ; 2 = GND
C9M6  CAP_A  0.1UF 16V 10% X7R  pkg 0402V  page 198 : 1 = P5V_STBY ; 2 = GND
C9M7  CAP_A  0.1UF 16V 10% X7R  pkg 0402V  page 163 : 1 = P3V3_STBY ; 2 = GND
C9M8  CAP_A  0.1UF 16V 10% X7R  pkg 0402V  page 163 : 1 = PVCCIO_CPU1 ; 2 = GND
C9M9  CAP_A  0.1UF 16V 10% X7R  pkg 0402V  page 198 : 1 = P12V_STBY ; 2 = GND
C9M10  CAP  10UF 16V 10% X6S  pkg 0805  page 198 : 1 = P12V_STBY ; 2 = GND
C9N1  CAP  0.22UF 16V 10% X7R  pkg 0402  page 182 : 1 = P3E_CPU1_PE3_MP_C_TXP<10> ; 2 = P3E_CPU1_PE3_MP_TXP<10>
C9N2  CAP  0.22UF 16V 10% X7R  pkg 0402  page 182 : 1 = P3E_CPU1_PE3_MP_C_TXN<10> ; 2 = P3E_CPU1_PE3_MP_TXN<10>
C9N3  CAP  0.22UF 16V 10% X7R  pkg 0402  page 182 : 1 = P3E_CPU1_PE3_MP_C_TXN<11> ; 2 = P3E_CPU1_PE3_MP_TXN<11>
C9N4  CAP  0.22UF 16V 10% X7R  pkg 0402  page 182 : 1 = P3E_CPU1_PE3_MP_C_TXP<11> ; 2 = P3E_CPU1_PE3_MP_TXP<11>
C9N5  CAP  0.22UF 16V 10% X7R  pkg 0402  page 182 : 1 = P3E_CPU1_PE3_MP_C_TXP<13> ; 2 = P3E_CPU1_PE3_MP_TXP<13>
C9N6  CAP  0.22UF 16V 10% X7R  pkg 0402  page 182 : 1 = P3E_CPU1_PE3_MP_C_TXN<13> ; 2 = P3E_CPU1_PE3_MP_TXN<13>
C9N7  CAP  0.22UF 16V 10% X7R  pkg 0402  page 182 : 1 = P3E_CPU1_PE3_MP_C_TXP<15> ; 2 = P3E_CPU1_PE3_MP_TXP<15>
C9N8  CAP  0.22UF 16V 10% X7R  pkg 0402  page 182 : 1 = P3E_CPU1_PE3_MP_C_TXN<14> ; 2 = P3E_CPU1_PE3_MP_TXN<14>
C9N9  CAP  0.22UF 16V 10% X7R  pkg 0402  page 182 : 1 = P3E_CPU1_PE3_MP_C_TXN<15> ; 2 = P3E_CPU1_PE3_MP_TXN<15>
C9N10  CAP  0.22UF 16V 10% X7R  pkg 0402  page 182 : 1 = P3E_CPU1_PE3_MP_C_TXP<14> ; 2 = P3E_CPU1_PE3_MP_TXP<14>
C9N11  CAPP  470UF 2.5V 20% ALUM  pkg 3018  page 210 : 1 = PVSA_CPU1 ; 2 = GND
C9N12  CAP  0.22UF 16V 10% X7R  pkg 0402  page 182 : 1 = P3E_CPU1_PE3_MP_C_TXP<9> ; 2 = P3E_CPU1_PE3_MP_TXP<9>
C9N13  CAP  10UF 16V 10% X6S  pkg 0805  page 210 : 1 = VR_FET_SW_P12V_STBY_PVCCIN_CPU1 ; 2 = GND
C9N14  CAP  0.22UF 16V 10% X7R  pkg 0402  page 182 : 1 = P3E_CPU1_PE3_MP_C_TXP<12> ; 2 = P3E_CPU1_PE3_MP_TXP<12>
C9N15  CAP  0.22UF 16V 10% X7R  pkg 0402  page 182 : 1 = P3E_CPU1_PE3_MP_C_TXN<9> ; 2 = P3E_CPU1_PE3_MP_TXN<9>
C9N16  CAP  0.22UF 16V 10% X7R  pkg 0402  page 182 : 1 = P3E_CPU1_PE3_MP_C_TXN<12> ; 2 = P3E_CPU1_PE3_MP_TXN<12>
C9N17  CAP  0.22UF 16V 10% X7R  pkg 0402  page 182 : 1 = P3E_CPU1_PE3_MP_C_TXP<8> ; 2 = P3E_CPU1_PE3_MP_TXP<8>
C9N18  CAP  0.22UF 16V 10% X7R  pkg 0402  page 182 : 1 = P3E_CPU1_PE3_MP_C_TXN<8> ; 2 = P3E_CPU1_PE3_MP_TXN<8>
C9N19  CAP  10UF 16V 10% X6S  pkg 0805  page 210 : 1 = VR_FET_SW_P12V_STBY_PVCCIN_CPU1 ; 2 = GND
C9N20  CAPP  470UF 2.5V 20% ALUM  pkg 3018  page 210 : 1 = PVSA_CPU1 ; 2 = GND
C9N21  CAP  10UF 16V 10% X6S  pkg 0805  page 210 : 1 = VR_FET_SW_P12V_STBY_PVCCIN_CPU1 ; 2 = GND
C9N22  CAP_A  22.0UF 4V 20% X6S  pkg 0603V  page 210 : 1 = PVSA_CPU1 ; 2 = GND
C9N24  CAPP  470UF 2.5V 20% ALUM  pkg 3018  page 208 : 1 = PVCCIN_CPU1 ; 2 = GND
C9N25  CAP  10UF 16V 10% X6S  pkg 0805  page 209 : 1 = VR_FET_SW_P12V_STBY_PVCCIN_CPU1 ; 2 = GND
C9N26  CAP  10UF 16V 10% X6S  pkg 0805  page 209 : 1 = VR_FET_SW_P12V_STBY_PVCCIN_CPU1 ; 2 = GND
C9N27  CAP  10UF 16V 10% X6S  pkg 0805  page 209 : 1 = VR_FET_SW_P12V_STBY_PVCCIN_CPU1 ; 2 = GND
C9P1  CAP  10UF 16V 10% X6S  pkg 0805  page 208 : 1 = VR_FET_SW_P12V_STBY_PVCCIN_CPU1 ; 2 = GND
C9P2  CAP  10UF 16V 10% X6S  pkg 0805  page 208 : 1 = VR_FET_SW_P12V_STBY_PVCCIN_CPU1 ; 2 = GND
C9P3  CAP_A  22.0UF 4V 20% X6S  pkg 0603V  page 207 : 1 = PVCCIN_CPU1 ; 2 = GND
C9P4  CAP  10UF 16V 10% X6S  pkg 0805  page 208 : 1 = VR_FET_SW_P12V_STBY_PVCCIN_CPU1 ; 2 = GND
C9P5  CAPP  470UF 2.5V 20% ALUM  pkg 3018  page 208 : 1 = PVCCIN_CPU1 ; 2 = GND
C9P6  CAP_A  0.1UF 16V 10% X7R  pkg 0402V  page 200 : 1 = P12V_STBY ; 2 = AGND_HSC
C9P7  CAP  10UF 16V 10% X6S  pkg 0805  page 208 : 1 = VR_FET_SW_P12V_STBY_PVCCIN_CPU1 ; 2 = GND
C9P8  CAPP  470UF 2.5V 20% ALUM  pkg 3018  page 208 : 1 = PVCCIN_CPU1 ; 2 = GND
C9P9  CAP  10UF 16V 10% X6S  pkg 0805  page 208 : 1 = VR_FET_SW_P12V_STBY_PVCCIN_CPU1 ; 2 = GND
C9P10  CAP_A  22.0UF 4V 20% X6S  pkg 0603V  page 208 : 1 = PVCCIN_CPU1 ; 2 = GND
C9P11  CAP_A  0.1UF 16V 10% X7R  pkg 0402V  page 200 : 1 = P3V3_STBY ; 2 = GND
C9P12  CAP_A  0.1UF 16V 10% EMPTY  pkg 0402V  page 199 : 1 = A_HSC_VOUT ; 2 = AGND_HSC
C9P14  CAP  0.033UF 50V 10% X7R  pkg 0603LF  page 199 : 1 = A_HSC_TIMER ; 2 = AGND_HSC
C9P15  CAP_A  0.1UF 16V 10% X7R  pkg 0402V  page 199 : 1 = A_HSC_ISET ; 2 = AGND_HSC
C9P16  CAP_A  0.1UF 16V 10% EMPTY  pkg 0402V  page 200 : 1 = A_HSC_MOP ; 2 = AGND_HSC
C9P17  CAP_A  0.1UF 16V 10% EMPTY  pkg 0402V  page 200 : 1 = A_HSC_MON ; 2 = AGND_HSC
C9P18  CAPP  470UF 2.5V 20% ALUM  pkg 3018  page 208 : 1 = PVCCIN_CPU1 ; 2 = GND
C9P20  CAP_A  22.0UF 4V 20% X6S  pkg 0603V  page 209 : 1 = PVCCIN_CPU1 ; 2 = GND
C9P22  CAP  10UF 16V 10% X6S  pkg 0805  page 207 : 1 = VR_FET_SW_P12V_STBY_PVCCIN_CPU1 ; 2 = GND
C9P23  CAPP  470UF 2.5V 20% ALUM  pkg 3018  page 208 : 1 = PVCCIN_CPU1 ; 2 = GND
C9P24  CAP  10UF 16V 10% X6S  pkg 0805  page 208 : 1 = VR_FET_SW_P12V_STBY_PVCCIN_CPU1 ; 2 = GND
C9P25  CAP  10UF 16V 10% X6S  pkg 0805  page 207 : 1 = VR_FET_SW_P12V_STBY_PVCCIN_CPU1 ; 2 = GND
C9P26  CAP  10UF 16V 10% X6S  pkg 0805  page 207 : 1 = VR_FET_SW_P12V_STBY_PVCCIN_CPU1 ; 2 = GND
C9R2  CAP_A  22.0UF 4V 20% X6S  pkg 0603V  page 208 : 1 = PVCCIN_CPU1 ; 2 = GND
C9R3  CAPP  470UF 2.5V 20% ALUM  pkg 3018  page 208 : 1 = PVCCIN_CPU1 ; 2 = GND
C9R5  CAP  10UF 16V 10% X6S  pkg 0805  page 195 : 1 = P12V_PSU ; 2 = GND
C9R6  CAP_A  0.1UF 16V 10% X7R  pkg 0402V  page 195 : 1 = P12V_PSU ; 2 = GND
C9R7  CAP  10UF 16V 10% X6S  pkg 0805  page 207 : 1 = VR_FET_SW_P12V_STBY_PVCCIN_CPU1 ; 2 = GND
C9R8  CAP_A  22.0UF 4V 20% X6S  pkg 0603V  page 207 : 1 = PVCCIN_CPU1 ; 2 = GND
C9R9  CAPP  470UF 2.5V 20% ALUM  pkg 3018  page 208 : 1 = PVCCIN_CPU1 ; 2 = GND
C9R10  CAP  10UF 16V 10% X6S  pkg 0805  page 207 : 1 = VR_FET_SW_P12V_STBY_PVCCIN_CPU1 ; 2 = GND
C9R11  CAP  10UF 16V 10% X6S  pkg 0805  page 207 : 1 = VR_FET_SW_P12V_STBY_PVCCIN_CPU1 ; 2 = GND
C9R12  CAP_A  0.1UF 16V 10% X7R  pkg 0402V  page 195 : 1 = P12V_PSU ; 2 = GND
C9R13  CAP_A  0.1UF 16V 10% X7R  pkg 0402V  page 167 : 1 = P3V3_STBY ; 2 = GND
C9R14  CAP_A  0.1UF 16V 10% X7R  pkg 0402V  page 167 : 1 = P3V3_STBY ; 2 = GND
C9T3  CAPP  68UF 16V 20% TANT  pkg 3018  page 195 : 1 = P12V_STBY ; 2 = GND
C9T4  CAP  10UF 16V 10% X6S  pkg 0805  page 224 : 1 = VR_FET_SW_P12V_STBY_PVDDQ_GHJ ; 2 = GND
C9T5  CAPP  470UF 2.5V 20% ALUM  pkg 3018  page 225 : 1 = PVDDQ_GHJ ; 2 = GND
C9T6  CAP  10UF 16V 10% X6S  pkg 0805  page 224 : 1 = VR_FET_SW_P12V_STBY_PVDDQ_GHJ ; 2 = GND
C9T7  CAP_A  0.01UF 25V 10% X7R  pkg 0402V  page 78 : 1 = M_G_VREF ; 2 = GND
C9T8  CAP  10UF 16V 10% X7R  pkg 0805  page 197 : 1 = P12V_NVDIMM_GHJ ; 2 = GND
C9T9  CAP  10UF 16V 10% X6S  pkg 0805  page 224 : 1 = VR_FET_SW_P12V_STBY_PVDDQ_GHJ ; 2 = GND
C9U2  CAPP  470UF 2.5V 20% ALUM  pkg 3018  page 225 : 1 = PVDDQ_GHJ ; 2 = GND
C9U3  CAP  10UF 16V 10% X6S  pkg 0805  page 224 : 1 = VR_FET_SW_P12V_STBY_PVDDQ_GHJ ; 2 = GND
C9U4  CAP  10UF 16V 10% X6S  pkg 0805  page 224 : 1 = VR_FET_SW_P12V_STBY_PVDDQ_GHJ ; 2 = GND
C9U5  CAPP  470UF 2.5V 20% ALUM  pkg 3018  page 225 : 1 = PVDDQ_GHJ ; 2 = GND
C9U6  CAP  10UF 16V 10% X6S  pkg 0805  page 224 : 1 = VR_FET_SW_P12V_STBY_PVDDQ_GHJ ; 2 = GND
C9U7  CAP_A  0.01UF 25V 10% X7R  pkg 0402V  page 79 : 1 = M_H_VREF ; 2 = GND
C9U8  CAP  10UF 16V 10% X7R  pkg 0805  page 197 : 1 = P12V_NVDIMM_GHJ ; 2 = GND
C9U9  CAPP  470UF 2.5V 20% ALUM  pkg 3018  page 225 : 1 = PVDDQ_GHJ ; 2 = GND
C9U10  CAP_A  0.01UF 25V 10% X7R  pkg 0402V  page 81 : 1 = M_J_VREF ; 2 = GND
C9U11  CAP  10UF 16V 10% X7R  pkg 0805  page 197 : 1 = P12V_NVDIMM_GHJ ; 2 = GND
C9W1  SC22P50V2JN-4GP  5%  pkg SMD-BCG  page 200 : 1 = A_P12V_STBY_FP_TRIGGER ; 2 = AGND_HSC
C9W2  SC22P50V2JN-4GP  5%  pkg SMD-BCG  page 200 : 1 = A_P12V_STBY_ADR_TRIGGER ; 2 = AGND_HSC
C9W5  CAP_A  0.1UF 16V 10% X7R  pkg 0402V  page 239 : 1 = P3V3_STBY ; 2 = GND
C9W6  CAP  1000PF 50V 10% EMPTY  pkg 0402LF  page 239 : 1 = PWRGD_P3V3_STBY ; 2 = GND
C9W7  CAP_A  0.1UF 16V 10% X7R  pkg 0402V  page 248 : 1 = P3V3_STBY ; 2 = GND
C9W8  CAP_A  0.1UF 16V 10% X7R  pkg 0402V  page 248 : 1 = PVCCIO_CPU0 ; 2 = GND
C9W10  CAP  1000PF 50V 10% X7R  pkg 0402LF  page 239 : 1 = PWRGD_P2V5_BMC_STBY_R ; 2 = GND
C9W13  CAP  22UF 4V 20% X6S  pkg 0805LF  page 239 : 1 = P2V5_AUX_BMC ; 2 = GND
C9W14  CAP  10UF 6.3V 20% X6S  pkg 0603  page 238 : 1 = P3V3_STBY ; 2 = GND
C9W16  CAP_A  22.0UF 4V 20% X6S  pkg 0603V  page 238 : 1 = P1V15_AUX_BMC ; 2 = GND
C9W17  CAP  10UF 6.3V 20% X6S  pkg 0603  page 239 : 1 = P3V3_STBY ; 2 = GND
C9W19  CAP_A  22.0UF 4V 20% X6S  pkg 0603V  page 239 : 1 = P1V2_AUX_BMC ; 2 = GND
C10W1  CAP  10UF 16V 10% X6S  pkg 0805  page 251 : 1 = P12V_PUMP ; 2 = GND
C10W2  CAP_A  0.1UF 16V 10% X7R  pkg 0402V  page 251 : 1 = P12V_PUMP ; 2 = GND
C10W3  CAP_A  0.01UF 25V 10% X7R  pkg 0402V  page 251 : 1 = PUMP_TACH0 ; 2 = GND
C10W4  CAP_A  0.1UF 16V 10% X7R  pkg 0402V  page 251 : 1 = P3V3_STBY ; 2 = GND
C10W5  CAP_A  0.01UF 25V 10% X7R  pkg 0402V  page 251 : 1 = PUMP_TACH1 ; 2 = GND
C12W1  CAP  47.0PF 50V 5% COG  pkg 0402LF  page 197 : 1 = VR_PVDDQ_ABC_AIINSEN ; 2 = VR_PVDDQ_ABC_VINSEN
C12W2  CAP  47.0PF 50V 5% COG  pkg 0402LF  page 197 : 1 = VR_PVDDQ_DEF_AIINSEN ; 2 = VR_PVDDQ_DEF_VINSEN
C12W3  CAP  47.0PF 50V 5% COG  pkg 0402LF  page 197 : 1 = VR_PVDDQ_GHJ_AIINSEN ; 2 = VR_PVDDQ_GHJ_VINSEN
C12W4  CAP  47.0PF 50V 5% COG  pkg 0402LF  page 197 : 1 = VR_PVDDQ_KLM_AIINSEN ; 2 = VR_PVDDQ_KLM_VINSEN
C14W1  CAP_A  0.1UF 16V 10% X7R  pkg 0402V  page 248 : 1 = P3V3 ; 2 = GND
C14W2  CAP_A  0.1UF 16V 10% X7R  pkg 0402V  page 248 : 1 = P3V3 ; 2 = GND
C22W1  SC22U16V5MX-4-GP  20%  pkg SMD-BCG5  page 225 : 1 = VR_FET_SW_P12V_STBY_PVDDQ_GHJ ; 2 = GND
C22W2  SC22U16V5MX-4-GP  20%  pkg SMD-BCG5  page 225 : 1 = VR_FET_SW_P12V_STBY_PVDDQ_GHJ ; 2 = GND
C22W3  SC22U16V5MX-4-GP  20%  pkg SMD-BCG5  page 225 : 1 = VR_FET_SW_P12V_STBY_PVDDQ_GHJ ; 2 = GND
C22W4  SC22U16V5MX-4-GP  20%  pkg SMD-BCG5  page 225 : 1 = VR_FET_SW_P12V_STBY_PVDDQ_GHJ ; 2 = GND
C22W5  SC22U16V5MX-4-GP  20%  pkg SMD-BCG5  page 234 : 1 = VR_FET_SW_P12V_STBY_PVPP_KLM ; 2 = GND
C22W6  SC22U16V5MX-4-GP  20%  pkg SMD-BCG5  page 233 : 1 = VR_FET_SW_P12V_STBY_PVPP_GHJ ; 2 = GND
C22W7  SC22U16V5MX-4-GP  20%  pkg SMD-BCG5  page 232 : 1 = VR_FET_SW_P12V_STBY_PVPP_DEF ; 2 = GND
C22W8  SC22U16V5MX-4-GP  20%  pkg SMD-BCG5  page 241 : 1 = VR_FET_SW_P5V_STBY_PVIN ; 2 = GND
C22W9  SC22U16V5MX-4-GP  20%  pkg SMD-BCG5  page 241 : 1 = VR_FET_SW_P5V_STBY_PVIN ; 2 = GND
C22W10  SC22U16V5MX-4-GP  20%  pkg SMD-BCG5  page 231 : 1 = VR_FET_SW_P12V_STBY_PVPP_ABC ; 2 = GND
C22W11  SC22U16V5MX-4-GP  20%  pkg SMD-BCG5  page 240 : 1 = VR_FET_SW_P12V_STBY_P3V3_STBY ; 2 = GND
C22W12  SC22U16V5MX-4-GP  20%  pkg SMD-BCG5  page 240 : 1 = VR_FET_SW_P12V_STBY_P3V3_STBY ; 2 = GND
C22W13  SC22U16V5MX-4-GP  20%  pkg SMD-BCG5  page 214 : 1 = VR_FET_SW_P12V_STBY_PVCCIN_CPU0 ; 2 = GND
C22W14  SC22U16V5MX-4-GP  20%  pkg SMD-BCG5  page 214 : 1 = VR_FET_SW_P12V_STBY_PVCCIN_CPU0 ; 2 = GND
C22W15  SC22U16V5MX-4-GP  20%  pkg SMD-BCG5  page 214 : 1 = VR_FET_SW_P12V_STBY_PVCCIN_CPU0 ; 2 = GND
C22W16  SC22U16V5MX-4-GP  20%  pkg SMD-BCG5  page 214 : 1 = VR_FET_SW_P12V_STBY_PVCCIN_CPU0 ; 2 = GND
C22W17  SC22U16V5MX-4-GP  20%  pkg SMD-BCG5  page 214 : 1 = VR_FET_SW_P12V_STBY_PVCCIN_CPU0 ; 2 = GND
C22W18  SC22U16V5MX-4-GP  20%  pkg SMD-BCG5  page 214 : 1 = VR_FET_SW_P12V_STBY_PVCCIN_CPU0 ; 2 = GND
C22W19  SC22U16V5MX-4-GP  20%  pkg SMD-BCG5  page 214 : 1 = VR_FET_SW_P12V_STBY_PVCCIN_CPU0 ; 2 = GND
C22W20  SC22U16V5MX-4-GP  20%  pkg SMD-BCG5  page 214 : 1 = VR_FET_SW_P12V_STBY_PVCCIN_CPU0 ; 2 = GND
C22W21  SC22U16V5MX-4-GP  20%  pkg SMD-BCG5  page 214 : 1 = VR_FET_SW_P12V_STBY_PVCCIN_CPU0 ; 2 = GND
C22W22  SC22U16V5MX-4-GP  20%  pkg SMD-BCG5  page 236 : 1 = VR_FET_SW_P12V_STBY_PVDDQ_DEF ; 2 = GND
C22W23  SC22U16V5MX-4-GP  20%  pkg SMD-BCG5  page 236 : 1 = VR_FET_SW_P12V_STBY_PVDDQ_DEF ; 2 = GND
C22W24  SC22U16V5MX-4-GP  20%  pkg SMD-BCG5  page 236 : 1 = VR_FET_SW_P12V_STBY_PVDDQ_DEF ; 2 = GND
C22W25  SC22U16V5MX-4-GP  20%  pkg SMD-BCG5  page 236 : 1 = VR_FET_SW_P12V_STBY_PVDDQ_DEF ; 2 = GND
C22W26  SC22U16V5MX-4-GP  20%  pkg SMD-BCG5  page 236 : 1 = VR_FET_SW_P12V_STBY_PVDDQ_DEF ; 2 = GND
C22W27  SC22U16V5MX-4-GP  20%  pkg SMD-BCG5  page 236 : 1 = VR_FET_SW_P12V_STBY_PVDDQ_DEF ; 2 = GND
C22W28  SC22U16V5MX-4-GP  20%  pkg SMD-BCG5  page 212 : 1 = VR_FET_SW_P12V_STBY_PVCCIO_CPU0 ; 2 = GND
C22W29  SC22U16V5MX-4-GP  20%  pkg SMD-BCG5  page 212 : 1 = VR_FET_SW_P12V_STBY_PVCCIO_CPU0 ; 2 = GND
C22W30  SC22U16V5MX-4-GP  20%  pkg SMD-BCG5  page 212 : 1 = VR_FET_SW_P12V_STBY_PVCCIO_CPU0 ; 2 = GND
C22W31  SC22U16V5MX-4-GP  20%  pkg SMD-BCG5  page 212 : 1 = VR_FET_SW_P12V_STBY_PVCCIO_CPU0 ; 2 = GND
C22W32  SC22U16V5MX-4-GP  20%  pkg SMD-BCG5  page 212 : 1 = VR_FET_SW_P12V_STBY_PVCCIO_CPU0 ; 2 = GND
C22W33  SC22U16V5MX-4-GP  20%  pkg SMD-BCG5  page 212 : 1 = VR_FET_SW_P12V_STBY_PVCCIO_CPU0 ; 2 = GND
